(kicad_pcb
	(version 20260206)
	(generator "pcbnew")
	(generator_version "10.0")
	(general
		(thickness 1.6)
		(legacy_teardrops no)
	)
	(paper "A4")
	(title_block
		(title "01162023_DA0F0TEBIF0_F0T_Expander_BD_F_brd_V02_OCP.brd")
		(comment 1 "Grand Teton / footprint 290 of 9728 (J5), pads 1-77 of 142")
	)
	(layers
		(0 "F.Cu" signal "TOP")
		(4 "In1.Cu" signal "GND")
		(6 "In2.Cu" signal "VCC")
		(8 "In3.Cu" signal "VCC1")
		(10 "In4.Cu" signal "GND1")
		(12 "In5.Cu" signal "IN1")
		(14 "In6.Cu" signal "GND2")
		(16 "In7.Cu" signal "IN2")
		(18 "In8.Cu" signal "GND3")
		(20 "In9.Cu" signal "IN3")
		(22 "In10.Cu" signal "GND4")
		(24 "In11.Cu" signal "IN4")
		(26 "In12.Cu" signal "GND5")
		(28 "In13.Cu" signal "IN5")
		(30 "In14.Cu" signal "GND6")
		(32 "In15.Cu" signal "IN6")
		(34 "In16.Cu" signal "GND7")
		(2 "B.Cu" signal "BOTTOM")
		(9 "F.Adhes" user "F.Adhesive")
		(11 "B.Adhes" user "B.Adhesive")
		(13 "F.Paste" user "Package Geometry/Pastemask Top")
		(15 "B.Paste" user "Package Geometry/Pastemask Bottom")
		(5 "F.SilkS" user "Ref Des/Silkscreen Top")
		(7 "B.SilkS" user "Ref Des/Silkscreen Bottom")
		(1 "F.Mask" user "Board Geometry/Soldermask Top")
		(3 "B.Mask" user "Board Geometry/Soldermask Bottom")
		(17 "Dwgs.User" user "User.Drawings")
		(19 "Cmts.User" user "User.Comments")
		(21 "Eco1.User" user "User.Eco1")
		(23 "Eco2.User" user "User.Eco2")
		(25 "Edge.Cuts" user "Board Geometry/Outline")
		(27 "Margin" user)
		(31 "F.CrtYd" user "Package Geometry/Place Bound Top")
		(29 "B.CrtYd" user "Package Geometry/Place Bound Bottom")
		(35 "F.Fab" user "Ref Des/Assembly Top")
		(33 "B.Fab" user "Ref Des/Assembly Bottom")
	)
	(footprint ""
		(layer "F.Cu")
		(at 159.910018 -412.090108)
		(property "Reference" "J5"
			(at -6.04647 3.572764 90)
			(unlocked yes)
			(layer "F.SilkS")
			(effects
				(font
					(size 2.032 1.524)
					(thickness 0.1524)
				)
				(justify left)
			)
		)
		(property "Value" ""
			(at 0 0 0)
			(layer "F.Fab")
			(effects
				(font
					(size 1.27 1.27)
				)
			)
		)
		(duplicate_pad_numbers_are_jumpers no)
		(pad "A1" thru_hole rect
			(at 0 0 180)
			(size 0.71628 0.71628)
			(drill 0.30988)
			(layers "*.Cu" "*.Mask")
			(remove_unused_layers no)
			(net "GPU_FPGA_EROT_RECOV_R_N")
			(clearance 0.0508)
			(thermal_gap 0.0508)
			(padstack
				(mode front_inner_back)
				(layer "Inner"
					(shape circle)
					(size 0.71628 0.71628)
					(clearance 0.0508)
				)
				(layer "B.Cu"
					(shape rect)
					(size 0.71628 0.71628)
					(clearance 0.0508)
				)
			)
		)
		(pad "A2" thru_hole circle
			(at 2.199894 0.199898 180)
			(size 0.906272 0.906272)
			(drill 0.499872)
			(layers "*.Cu" "*.Mask")
			(remove_unused_layers no)
			(net "GND")
			(clearance 0.0508)
			(thermal_gap 0.0508)
		)
		(pad "A3" thru_hole circle
			(at 4.400042 0 180)
			(size 0.71628 0.71628)
			(drill 0.30988)
			(layers "*.Cu" "*.Mask")
			(remove_unused_layers no)
			(net "PRSNT_GPU_HMC_N")
			(clearance 0.0508)
			(thermal_gap 0.0508)
		)
		(pad "A4" thru_hole circle
			(at 6.599936 0.199898 180)
			(size 0.906272 0.906272)
			(drill 0.499872)
			(layers "*.Cu" "*.Mask")
			(remove_unused_layers no)
			(net "GND")
			(clearance 0.0508)
			(thermal_gap 0.0508)
		)
		(pad "A5" thru_hole circle
			(at 8.800084 0 180)
			(size 0.71628 0.71628)
			(drill 0.30988)
			(layers "*.Cu" "*.Mask")
			(remove_unused_layers no)
			(net "GPU_BASE_HMC_READY")
			(clearance 0.0508)
			(thermal_gap 0.0508)
		)
		(pad "A6" thru_hole circle
			(at 10.999978 0.199898 180)
			(size 0.906272 0.906272)
			(drill 0.499872)
			(layers "*.Cu" "*.Mask")
			(remove_unused_layers no)
			(net "GND")
			(clearance 0.0508)
			(thermal_gap 0.0508)
		)
		(pad "A7" thru_hole circle
			(at 13.199872 0 180)
			(size 0.71628 0.71628)
			(drill 0.30988)
			(layers "*.Cu" "*.Mask")
			(remove_unused_layers no)
			(net "GPU_BASE_STBY_EN_R")
			(clearance 0.0508)
			(thermal_gap 0.0508)
		)
		(pad "A8" thru_hole circle
			(at 15.40002 0.199898 180)
			(size 0.906272 0.906272)
			(drill 0.499872)
			(layers "*.Cu" "*.Mask")
			(remove_unused_layers no)
			(net "GND")
			(clearance 0.0508)
			(thermal_gap 0.0508)
		)
		(pad "A9" thru_hole circle
			(at 17.599914 0 180)
			(size 0.71628 0.71628)
			(drill 0.30988)
			(layers "*.Cu" "*.Mask")
			(remove_unused_layers no)
			(net "Net_40")
			(clearance 0.0508)
			(thermal_gap 0.0508)
		)
		(pad "A10" thru_hole circle
			(at 19.800062 0.199898 180)
			(size 0.906272 0.906272)
			(drill 0.499872)
			(layers "*.Cu" "*.Mask")
			(remove_unused_layers no)
			(net "GND")
			(clearance 0.0508)
			(thermal_gap 0.0508)
		)
		(pad "B1" thru_hole circle
			(at 0 1.299972 180)
			(size 0.906272 0.906272)
			(drill 0.499872)
			(layers "*.Cu" "*.Mask")
			(remove_unused_layers no)
			(net "GND")
			(clearance 0.0508)
			(thermal_gap 0.0508)
		)
		(pad "B3" thru_hole circle
			(at 4.400042 1.299972 180)
			(size 0.906272 0.906272)
			(drill 0.499872)
			(layers "*.Cu" "*.Mask")
			(remove_unused_layers no)
			(net "GND")
			(clearance 0.0508)
			(thermal_gap 0.0508)
		)
		(pad "B5" thru_hole circle
			(at 8.800084 1.299972 180)
			(size 0.906272 0.906272)
			(drill 0.499872)
			(layers "*.Cu" "*.Mask")
			(remove_unused_layers no)
			(net "GND")
			(clearance 0.0508)
			(thermal_gap 0.0508)
		)
		(pad "B7" thru_hole circle
			(at 13.199872 1.299972 180)
			(size 0.906272 0.906272)
			(drill 0.499872)
			(layers "*.Cu" "*.Mask")
			(remove_unused_layers no)
			(net "GND")
			(clearance 0.0508)
			(thermal_gap 0.0508)
		)
		(pad "B9" thru_hole circle
			(at 17.599914 1.299972 180)
			(size 0.906272 0.906272)
			(drill 0.499872)
			(layers "*.Cu" "*.Mask")
			(remove_unused_layers no)
			(net "GND")
			(clearance 0.0508)
			(thermal_gap 0.0508)
		)
		(pad "B10" thru_hole circle
			(at 19.800062 1.500124 180)
			(size 0.71628 0.71628)
			(drill 0.30988)
			(layers "*.Cu" "*.Mask")
			(remove_unused_layers no)
			(net "Net_8845")
			(clearance 0.0508)
			(thermal_gap 0.0508)
		)
		(pad "C9" thru_hole circle
			(at 17.599914 2.599944 180)
			(size 0.71628 0.71628)
			(drill 0.30988)
			(layers "*.Cu" "*.Mask")
			(remove_unused_layers no)
			(net "SMB_GPU2_ALERT_N")
			(clearance 0.0508)
			(thermal_gap 0.0508)
		)
		(pad "C10" thru_hole circle
			(at 19.800062 2.800096 180)
			(size 0.71628 0.71628)
			(drill 0.30988)
			(layers "*.Cu" "*.Mask")
			(remove_unused_layers no)
			(net "Net_8844")
			(clearance 0.0508)
			(thermal_gap 0.0508)
		)
		(pad "D2" thru_hole circle
			(at 2.199894 4.100068 180)
			(size 0.906272 0.906272)
			(drill 0.499872)
			(layers "*.Cu" "*.Mask")
			(remove_unused_layers no)
			(net "GND")
			(clearance 0.0508)
			(thermal_gap 0.0508)
		)
		(pad "D4" thru_hole circle
			(at 6.599936 4.100068 180)
			(size 0.906272 0.906272)
			(drill 0.499872)
			(layers "*.Cu" "*.Mask")
			(remove_unused_layers no)
			(net "GND")
			(clearance 0.0508)
			(thermal_gap 0.0508)
		)
		(pad "D6" thru_hole circle
			(at 10.999978 4.100068 180)
			(size 0.906272 0.906272)
			(drill 0.499872)
			(layers "*.Cu" "*.Mask")
			(remove_unused_layers no)
			(net "GND")
			(clearance 0.0508)
			(thermal_gap 0.0508)
		)
		(pad "D8" thru_hole circle
			(at 15.40002 4.100068 180)
			(size 0.906272 0.906272)
			(drill 0.499872)
			(layers "*.Cu" "*.Mask")
			(remove_unused_layers no)
			(net "GND")
			(clearance 0.0508)
			(thermal_gap 0.0508)
		)
		(pad "D9" thru_hole circle
			(at 17.599914 3.899916 180)
			(size 0.71628 0.71628)
			(drill 0.30988)
			(layers "*.Cu" "*.Mask")
			(remove_unused_layers no)
			(net "GPU_RSVD_PARTNER2")
			(clearance 0.0508)
			(thermal_gap 0.0508)
		)
		(pad "D10" thru_hole circle
			(at 19.800062 4.100068 180)
			(size 0.906272 0.906272)
			(drill 0.499872)
			(layers "*.Cu" "*.Mask")
			(remove_unused_layers no)
			(net "GND")
			(clearance 0.0508)
			(thermal_gap 0.0508)
		)
		(pad "E1" thru_hole circle
			(at 0 5.199888 180)
			(size 0.906272 0.906272)
			(drill 0.499872)
			(layers "*.Cu" "*.Mask")
			(remove_unused_layers no)
			(net "GND")
			(clearance 0.0508)
			(thermal_gap 0.0508)
		)
		(pad "E3" thru_hole circle
			(at 4.400042 5.199888 180)
			(size 0.906272 0.906272)
			(drill 0.499872)
			(layers "*.Cu" "*.Mask")
			(remove_unused_layers no)
			(net "GND")
			(clearance 0.0508)
			(thermal_gap 0.0508)
		)
		(pad "E5" thru_hole circle
			(at 8.800084 5.199888 180)
			(size 0.906272 0.906272)
			(drill 0.499872)
			(layers "*.Cu" "*.Mask")
			(remove_unused_layers no)
			(net "GND")
			(clearance 0.0508)
			(thermal_gap 0.0508)
		)
		(pad "E7" thru_hole circle
			(at 13.199872 5.199888 180)
			(size 0.906272 0.906272)
			(drill 0.499872)
			(layers "*.Cu" "*.Mask")
			(remove_unused_layers no)
			(net "GND")
			(clearance 0.0508)
			(thermal_gap 0.0508)
		)
		(pad "E9" thru_hole circle
			(at 17.599914 5.199888 180)
			(size 0.906272 0.906272)
			(drill 0.499872)
			(layers "*.Cu" "*.Mask")
			(remove_unused_layers no)
			(net "GND")
			(clearance 0.0508)
			(thermal_gap 0.0508)
		)
		(pad "E10" thru_hole circle
			(at 19.800062 5.40004 180)
			(size 0.71628 0.71628)
			(drill 0.30988)
			(layers "*.Cu" "*.Mask")
			(remove_unused_layers no)
			(net "Net_8843")
			(clearance 0.0508)
			(thermal_gap 0.0508)
		)
		(pad "F9" thru_hole circle
			(at 17.599914 6.500114 180)
			(size 0.71628 0.71628)
			(drill 0.30988)
			(layers "*.Cu" "*.Mask")
			(remove_unused_layers no)
			(net "SMB_GPU1_ALERT_N")
			(clearance 0.0508)
			(thermal_gap 0.0508)
		)
		(pad "F10" thru_hole circle
			(at 19.800062 6.700012 180)
			(size 0.71628 0.71628)
			(drill 0.30988)
			(layers "*.Cu" "*.Mask")
			(remove_unused_layers no)
			(net "Net_8842")
			(clearance 0.0508)
			(thermal_gap 0.0508)
		)
		(pad "G2" thru_hole circle
			(at 2.199894 7.999984 180)
			(size 0.906272 0.906272)
			(drill 0.499872)
			(layers "*.Cu" "*.Mask")
			(remove_unused_layers no)
			(net "GND")
			(clearance 0.0508)
			(thermal_gap 0.0508)
		)
		(pad "G4" thru_hole circle
			(at 6.599936 7.999984 180)
			(size 0.906272 0.906272)
			(drill 0.499872)
			(layers "*.Cu" "*.Mask")
			(remove_unused_layers no)
			(net "GND")
			(clearance 0.0508)
			(thermal_gap 0.0508)
		)
		(pad "G6" thru_hole circle
			(at 10.999978 7.999984 180)
			(size 0.906272 0.906272)
			(drill 0.499872)
			(layers "*.Cu" "*.Mask")
			(remove_unused_layers no)
			(net "GND")
			(clearance 0.0508)
			(thermal_gap 0.0508)
		)
		(pad "G8" thru_hole circle
			(at 15.40002 7.999984 180)
			(size 0.906272 0.906272)
			(drill 0.499872)
			(layers "*.Cu" "*.Mask")
			(remove_unused_layers no)
			(net "GND")
			(clearance 0.0508)
			(thermal_gap 0.0508)
		)
		(pad "G9" thru_hole circle
			(at 17.599914 7.800086 180)
			(size 0.71628 0.71628)
			(drill 0.30988)
			(layers "*.Cu" "*.Mask")
			(remove_unused_layers no)
			(net "GPU_RSVD_PARTNER1")
			(clearance 0.0508)
			(thermal_gap 0.0508)
		)
		(pad "G10" thru_hole circle
			(at 19.800062 7.999984 180)
			(size 0.906272 0.906272)
			(drill 0.499872)
			(layers "*.Cu" "*.Mask")
			(remove_unused_layers no)
			(net "GND")
			(clearance 0.0508)
			(thermal_gap 0.0508)
		)
		(pad "H1" thru_hole circle
			(at 0 9.100058 180)
			(size 0.906272 0.906272)
			(drill 0.499872)
			(layers "*.Cu" "*.Mask")
			(remove_unused_layers no)
			(net "GND")
			(clearance 0.0508)
			(thermal_gap 0.0508)
		)
		(pad "H3" thru_hole circle
			(at 4.400042 9.100058 180)
			(size 0.906272 0.906272)
			(drill 0.499872)
			(layers "*.Cu" "*.Mask")
			(remove_unused_layers no)
			(net "GND")
			(clearance 0.0508)
			(thermal_gap 0.0508)
		)
		(pad "H5" thru_hole circle
			(at 8.800084 9.100058 180)
			(size 0.906272 0.906272)
			(drill 0.499872)
			(layers "*.Cu" "*.Mask")
			(remove_unused_layers no)
			(net "GND")
			(clearance 0.0508)
			(thermal_gap 0.0508)
		)
		(pad "H7" thru_hole circle
			(at 13.199872 9.100058 180)
			(size 0.906272 0.906272)
			(drill 0.499872)
			(layers "*.Cu" "*.Mask")
			(remove_unused_layers no)
			(net "GND")
			(clearance 0.0508)
			(thermal_gap 0.0508)
		)
		(pad "H9" thru_hole circle
			(at 17.599914 9.100058 180)
			(size 0.906272 0.906272)
			(drill 0.499872)
			(layers "*.Cu" "*.Mask")
			(remove_unused_layers no)
			(net "GND")
			(clearance 0.0508)
			(thermal_gap 0.0508)
		)
		(pad "H10" thru_hole circle
			(at 19.800062 9.299956 180)
			(size 0.71628 0.71628)
			(drill 0.30988)
			(layers "*.Cu" "*.Mask")
			(remove_unused_layers no)
			(net "GPU_FPGA_BOOT_EN_R")
			(clearance 0.0508)
			(thermal_gap 0.0508)
		)
		(pad "I9" thru_hole circle
			(at 17.599914 10.40003 180)
			(size 0.71628 0.71628)
			(drill 0.30988)
			(layers "*.Cu" "*.Mask")
			(remove_unused_layers no)
			(net "Net_8841")
			(clearance 0.0508)
			(thermal_gap 0.0508)
		)
		(pad "I10" thru_hole circle
			(at 19.800062 10.599928 180)
			(size 0.71628 0.71628)
			(drill 0.30988)
			(layers "*.Cu" "*.Mask")
			(remove_unused_layers no)
			(net "GPU_RSVD_PARTNER0")
			(clearance 0.0508)
			(thermal_gap 0.0508)
		)
		(pad "J2" thru_hole circle
			(at 2.199894 11.8999 180)
			(size 0.906272 0.906272)
			(drill 0.499872)
			(layers "*.Cu" "*.Mask")
			(remove_unused_layers no)
			(net "GND")
			(clearance 0.0508)
			(thermal_gap 0.0508)
		)
		(pad "J4" thru_hole circle
			(at 6.599936 11.8999 180)
			(size 0.906272 0.906272)
			(drill 0.499872)
			(layers "*.Cu" "*.Mask")
			(remove_unused_layers no)
			(net "GND")
			(clearance 0.0508)
			(thermal_gap 0.0508)
		)
		(pad "J6" thru_hole circle
			(at 10.999978 11.8999 180)
			(size 0.906272 0.906272)
			(drill 0.499872)
			(layers "*.Cu" "*.Mask")
			(remove_unused_layers no)
			(net "GND")
			(clearance 0.0508)
			(thermal_gap 0.0508)
		)
		(pad "J8" thru_hole circle
			(at 15.40002 11.8999 180)
			(size 0.906272 0.906272)
			(drill 0.499872)
			(layers "*.Cu" "*.Mask")
			(remove_unused_layers no)
			(net "GND")
			(clearance 0.0508)
			(thermal_gap 0.0508)
		)
		(pad "J9" thru_hole circle
			(at 17.599914 11.700002 180)
			(size 0.71628 0.71628)
			(drill 0.30988)
			(layers "*.Cu" "*.Mask")
			(remove_unused_layers no)
			(net "Net_8840")
			(clearance 0.0508)
			(thermal_gap 0.0508)
		)
		(pad "J10" thru_hole circle
			(at 19.800062 11.8999 180)
			(size 0.906272 0.906272)
			(drill 0.499872)
			(layers "*.Cu" "*.Mask")
			(remove_unused_layers no)
			(net "GND")
			(clearance 0.0508)
			(thermal_gap 0.0508)
		)
		(pad "K1" thru_hole circle
			(at 0 12.999974 180)
			(size 0.906272 0.906272)
			(drill 0.499872)
			(layers "*.Cu" "*.Mask")
			(remove_unused_layers no)
			(net "GND")
			(clearance 0.0508)
			(thermal_gap 0.0508)
		)
		(pad "K3" thru_hole circle
			(at 4.400042 12.999974 180)
			(size 0.906272 0.906272)
			(drill 0.499872)
			(layers "*.Cu" "*.Mask")
			(remove_unused_layers no)
			(net "GND")
			(clearance 0.0508)
			(thermal_gap 0.0508)
		)
		(pad "K5" thru_hole circle
			(at 8.800084 12.999974 180)
			(size 0.906272 0.906272)
			(drill 0.499872)
			(layers "*.Cu" "*.Mask")
			(remove_unused_layers no)
			(net "GND")
			(clearance 0.0508)
			(thermal_gap 0.0508)
		)
		(pad "K7" thru_hole circle
			(at 13.199872 12.999974 180)
			(size 0.906272 0.906272)
			(drill 0.499872)
			(layers "*.Cu" "*.Mask")
			(remove_unused_layers no)
			(net "GND")
			(clearance 0.0508)
			(thermal_gap 0.0508)
		)
		(pad "K9" thru_hole circle
			(at 17.599914 12.999974 180)
			(size 0.906272 0.906272)
			(drill 0.499872)
			(layers "*.Cu" "*.Mask")
			(remove_unused_layers no)
			(net "GND")
			(clearance 0.0508)
			(thermal_gap 0.0508)
		)
		(pad "K10" thru_hole circle
			(at 19.800062 13.199872 180)
			(size 0.71628 0.71628)
			(drill 0.30988)
			(layers "*.Cu" "*.Mask")
			(remove_unused_layers no)
			(net "Net_8839")
			(clearance 0.0508)
			(thermal_gap 0.0508)
		)
		(pad "L9" thru_hole circle
			(at 17.599914 14.299946 180)
			(size 0.71628 0.71628)
			(drill 0.30988)
			(layers "*.Cu" "*.Mask")
			(remove_unused_layers no)
			(net "Net_8837")
			(clearance 0.0508)
			(thermal_gap 0.0508)
		)
		(pad "L10" thru_hole circle
			(at 19.800062 14.500098 180)
			(size 0.71628 0.71628)
			(drill 0.30988)
			(layers "*.Cu" "*.Mask")
			(remove_unused_layers no)
			(net "Net_8838")
			(clearance 0.0508)
			(thermal_gap 0.0508)
		)
		(pad "M1_2" thru_hole circle
			(at 2.199894 15.80007 180)
			(size 0.906272 0.906272)
			(drill 0.499872)
			(layers "*.Cu" "*.Mask")
			(remove_unused_layers no)
			(net "GND")
			(clearance 0.0508)
			(thermal_gap 0.0508)
		)
		(pad "M1_4" thru_hole circle
			(at 6.599936 15.80007 180)
			(size 0.906272 0.906272)
			(drill 0.499872)
			(layers "*.Cu" "*.Mask")
			(remove_unused_layers no)
			(net "GND")
			(clearance 0.0508)
			(thermal_gap 0.0508)
		)
		(pad "M1_6" thru_hole circle
			(at 10.999978 15.80007 180)
			(size 0.906272 0.906272)
			(drill 0.499872)
			(layers "*.Cu" "*.Mask")
			(remove_unused_layers no)
			(net "GND")
			(clearance 0.0508)
			(thermal_gap 0.0508)
		)
		(pad "M1_8" thru_hole circle
			(at 15.40002 15.80007 180)
			(size 0.906272 0.906272)
			(drill 0.499872)
			(layers "*.Cu" "*.Mask")
			(remove_unused_layers no)
			(net "GND")
			(clearance 0.0508)
			(thermal_gap 0.0508)
		)
		(pad "M1_10" thru_hole circle
			(at 19.800062 15.80007 180)
			(size 0.906272 0.906272)
			(drill 0.499872)
			(layers "*.Cu" "*.Mask")
			(remove_unused_layers no)
			(net "GND")
			(clearance 0.0508)
			(thermal_gap 0.0508)
		)
		(pad "M2_2" thru_hole circle
			(at 2.199894 26.2001 180)
			(size 0.906272 0.906272)
			(drill 0.499872)
			(layers "*.Cu" "*.Mask")
			(remove_unused_layers no)
			(net "GND")
			(clearance 0.0508)
			(thermal_gap 0.0508)
		)
		(pad "M2_4" thru_hole circle
			(at 6.599936 26.2001 180)
			(size 0.906272 0.906272)
			(drill 0.499872)
			(layers "*.Cu" "*.Mask")
			(remove_unused_layers no)
			(net "GND")
			(clearance 0.0508)
			(thermal_gap 0.0508)
		)
		(pad "M2_6" thru_hole circle
			(at 10.999978 26.2001 180)
			(size 0.906272 0.906272)
			(drill 0.499872)
			(layers "*.Cu" "*.Mask")
			(remove_unused_layers no)
			(net "GND")
			(clearance 0.0508)
			(thermal_gap 0.0508)
		)
		(pad "M2_8" thru_hole circle
			(at 15.40002 26.2001 180)
			(size 0.906272 0.906272)
			(drill 0.499872)
			(layers "*.Cu" "*.Mask")
			(remove_unused_layers no)
			(net "GND")
			(clearance 0.0508)
			(thermal_gap 0.0508)
		)
		(pad "M2_10" thru_hole circle
			(at 19.800062 26.2001 180)
			(size 0.906272 0.906272)
			(drill 0.499872)
			(layers "*.Cu" "*.Mask")
			(remove_unused_layers no)
			(net "GND")
			(clearance 0.0508)
			(thermal_gap 0.0508)
		)
		(pad "M9" thru_hole circle
			(at 17.599914 15.599918 180)
			(size 0.71628 0.71628)
			(drill 0.30988)
			(layers "*.Cu" "*.Mask")
			(remove_unused_layers no)
			(net "Net_8836")
			(clearance 0.0508)
			(thermal_gap 0.0508)
		)
		(pad "N1_1" thru_hole circle
			(at 0 16.89989 180)
			(size 0.906272 0.906272)
			(drill 0.499872)
			(layers "*.Cu" "*.Mask")
			(remove_unused_layers no)
			(net "GND")
			(clearance 0.0508)
			(thermal_gap 0.0508)
		)
		(pad "N1_3" thru_hole circle
			(at 4.400042 16.89989 180)
			(size 0.906272 0.906272)
			(drill 0.499872)
			(layers "*.Cu" "*.Mask")
			(remove_unused_layers no)
			(net "GND")
			(clearance 0.0508)
			(thermal_gap 0.0508)
		)
		(pad "N1_5" thru_hole circle
			(at 8.800084 16.89989 180)
			(size 0.906272 0.906272)
			(drill 0.499872)
			(layers "*.Cu" "*.Mask")
			(remove_unused_layers no)
			(net "GND")
			(clearance 0.0508)
			(thermal_gap 0.0508)
		)
		(pad "N1_7" thru_hole circle
			(at 13.199872 16.89989 180)
			(size 0.906272 0.906272)
			(drill 0.499872)
			(layers "*.Cu" "*.Mask")
			(remove_unused_layers no)
			(net "GND")
			(clearance 0.0508)
			(thermal_gap 0.0508)
		)
		(pad "N1_9" thru_hole circle
			(at 17.599914 16.89989 180)
			(size 0.906272 0.906272)
			(drill 0.499872)
			(layers "*.Cu" "*.Mask")
			(remove_unused_layers no)
			(net "GND")
			(clearance 0.0508)
			(thermal_gap 0.0508)
		)
		(pad "N2_1" thru_hole circle
			(at 0 27.29992 180)
			(size 0.906272 0.906272)
			(drill 0.499872)
			(layers "*.Cu" "*.Mask")
			(remove_unused_layers no)
			(net "GND")
			(clearance 0.0508)
			(thermal_gap 0.0508)
		)
	)
)
